(kicad_pcb
	(version 20260206)
	(generator "pcbnew")
	(generator_version "10.0")
	(general
		(thickness 1.6)
		(legacy_teardrops no)
	)
	(paper "A4")
	(title_block
		(title "03242023_DA0F0TMBIJ0_F0T_Motherboard_J_brd_V01_OCP.brd")
		(comment 1 "Grand Teton / footprints 3400-3405 of 6105")
	)
	(layers
		(0 "F.Cu" signal "TOP")
		(4 "In1.Cu" signal "GND")
		(6 "In2.Cu" signal "IN1")
		(8 "In3.Cu" signal "GND1")
		(10 "In4.Cu" signal "IN2")
		(12 "In5.Cu" signal "GND2")
		(14 "In6.Cu" signal "IN3")
		(16 "In7.Cu" signal "GND3")
		(18 "In8.Cu" signal "VCC")
		(20 "In9.Cu" signal "VCC1")
		(22 "In10.Cu" signal "GND4")
		(24 "In11.Cu" signal "IN4")
		(26 "In12.Cu" signal "GND5")
		(28 "In13.Cu" signal "IN5")
		(30 "In14.Cu" signal "GND6")
		(32 "In15.Cu" signal "IN6")
		(34 "In16.Cu" signal "GND7")
		(2 "B.Cu" signal "BOTTOM")
		(9 "F.Adhes" user "F.Adhesive")
		(11 "B.Adhes" user "B.Adhesive")
		(13 "F.Paste" user "Package Geometry/Pastemask Top")
		(15 "B.Paste" user "Package Geometry/Pastemask Bottom")
		(5 "F.SilkS" user "Ref Des/Silkscreen Top")
		(7 "B.SilkS" user "Ref Des/Silkscreen Bottom")
		(1 "F.Mask" user "Board Geometry/Soldermask Top")
		(3 "B.Mask" user "Board Geometry/Soldermask Bottom")
		(17 "Dwgs.User" user "User.Drawings")
		(19 "Cmts.User" user "User.Comments")
		(21 "Eco1.User" user "User.Eco1")
		(23 "Eco2.User" user "User.Eco2")
		(25 "Edge.Cuts" user "Board Geometry/Outline")
		(27 "Margin" user)
		(31 "F.CrtYd" user "Package Geometry/Place Bound Top")
		(29 "B.CrtYd" user "Package Geometry/Place Bound Bottom")
		(35 "F.Fab" user "Ref Des/Assembly Top")
		(33 "B.Fab" user "Ref Des/Assembly Bottom")
	)
	(footprint ""
		(layer "F.Cu")
		(at 40.300402 -180.55336 180)
		(property "Reference" "C1403"
			(at 0 0 180)
			(layer "F.SilkS")
			(hide yes)
			(effects
				(font
					(size 1.27 1.27)
				)
			)
		)
		(property "Value" ""
			(at 0 0 180)
			(layer "F.Fab")
			(effects
				(font
					(size 1.27 1.27)
				)
			)
		)
		(duplicate_pad_numbers_are_jumpers no)
		(fp_line
			(start 1.524 0.762)
			(end -1.524 0.762)
			(stroke
				(width 0.1524)
				(type default)
			)
			(layer "F.SilkS")
		)
		(fp_line
			(start 1.524 -0.762)
			(end 1.524 0.762)
			(stroke
				(width 0.1524)
				(type default)
			)
			(layer "F.SilkS")
		)
		(fp_line
			(start -1.524 0.762)
			(end -1.524 -0.762)
			(stroke
				(width 0.1524)
				(type default)
			)
			(layer "F.SilkS")
		)
		(fp_line
			(start -1.524 -0.762)
			(end 1.524 -0.762)
			(stroke
				(width 0.1524)
				(type default)
			)
			(layer "F.SilkS")
		)
		(fp_line
			(start 1.1049 0.724916)
			(end 1.1049 -0.724916)
			(stroke
				(width 0.1)
				(type default)
			)
			(layer "F.Fab")
		)
		(fp_line
			(start 1.1049 -0.724916)
			(end -1.1049 -0.724916)
			(stroke
				(width 0.1)
				(type default)
			)
			(layer "F.Fab")
		)
		(fp_line
			(start -1.1049 0.724916)
			(end 1.1049 0.724916)
			(stroke
				(width 0.1)
				(type default)
			)
			(layer "F.Fab")
		)
		(fp_line
			(start -1.1049 -0.724916)
			(end -1.1049 0.724916)
			(stroke
				(width 0.1)
				(type default)
			)
			(layer "F.Fab")
		)
		(pad "1" smd rect
			(at -0.889 0)
			(size 1.016 1.27)
			(layers "F.Cu" "F.Mask" "F.Paste")
			(net "PVNN_MAIN_CPU1")
		)
		(pad "2" smd rect
			(at 0.889 0)
			(size 1.016 1.27)
			(layers "F.Cu" "F.Mask" "F.Paste")
			(net "GND")
		)
	)
	(footprint ""
		(layer "F.Cu")
		(at 332.433168 -23.571454 -90)
		(property "Reference" "R2363"
			(at 0 0 270)
			(layer "F.SilkS")
			(hide yes)
			(effects
				(font
					(size 1.27 1.27)
				)
			)
		)
		(property "Value" ""
			(at 0 0 270)
			(layer "F.Fab")
			(effects
				(font
					(size 1.27 1.27)
				)
			)
		)
		(duplicate_pad_numbers_are_jumpers no)
		(fp_line
			(start -0.7874 0.4064)
			(end -0.7874 -0.4064)
			(stroke
				(width 0.1524)
				(type default)
			)
			(layer "F.SilkS")
		)
		(fp_line
			(start 0.7874 0.4064)
			(end -0.7874 0.4064)
			(stroke
				(width 0.1524)
				(type default)
			)
			(layer "F.SilkS")
		)
		(fp_line
			(start -0.7874 -0.4064)
			(end 0.7874 -0.4064)
			(stroke
				(width 0.1524)
				(type default)
			)
			(layer "F.SilkS")
		)
		(fp_line
			(start 0.7874 -0.4064)
			(end 0.7874 0.4064)
			(stroke
				(width 0.1524)
				(type default)
			)
			(layer "F.SilkS")
		)
		(fp_line
			(start -0.67945 0.3048)
			(end -0.67945 -0.305054)
			(stroke
				(width 0.1)
				(type default)
			)
			(layer "F.Fab")
		)
		(fp_line
			(start -0.12065 0.3048)
			(end -0.67945 0.3048)
			(stroke
				(width 0.1)
				(type default)
			)
			(layer "F.Fab")
		)
		(fp_line
			(start 0.120396 0.3048)
			(end 0.120396 0.2794)
			(stroke
				(width 0.1)
				(type default)
			)
			(layer "F.Fab")
		)
		(fp_line
			(start 0.67945 0.3048)
			(end 0.120396 0.3048)
			(stroke
				(width 0.1)
				(type default)
			)
			(layer "F.Fab")
		)
		(fp_line
			(start -0.12065 0.2794)
			(end -0.12065 0.3048)
			(stroke
				(width 0.1)
				(type default)
			)
			(layer "F.Fab")
		)
		(fp_line
			(start 0.120396 0.2794)
			(end -0.12065 0.2794)
			(stroke
				(width 0.1)
				(type default)
			)
			(layer "F.Fab")
		)
		(fp_line
			(start -0.12065 -0.2794)
			(end 0.12065 -0.2794)
			(stroke
				(width 0.1)
				(type default)
			)
			(layer "F.Fab")
		)
		(fp_line
			(start 0.12065 -0.2794)
			(end 0.12065 -0.3048)
			(stroke
				(width 0.1)
				(type default)
			)
			(layer "F.Fab")
		)
		(fp_line
			(start 0.12065 -0.3048)
			(end 0.67945 -0.3048)
			(stroke
				(width 0.1)
				(type default)
			)
			(layer "F.Fab")
		)
		(fp_line
			(start 0.67945 -0.3048)
			(end 0.67945 0.3048)
			(stroke
				(width 0.1)
				(type default)
			)
			(layer "F.Fab")
		)
		(fp_line
			(start -0.67945 -0.305054)
			(end -0.12065 -0.305054)
			(stroke
				(width 0.1)
				(type default)
			)
			(layer "F.Fab")
		)
		(fp_line
			(start -0.12065 -0.305054)
			(end -0.12065 -0.2794)
			(stroke
				(width 0.1)
				(type default)
			)
			(layer "F.Fab")
		)
		(pad "1" smd circle
			(at -0.40005 0 270)
			(size 0 0)
			(layers "F.Cu" "F.Mask" "F.Paste")
			(net "RST_ESPI_RESET_N")
		)
		(pad "2" smd circle
			(at 0.40005 0 270)
			(size 0 0)
			(layers "F.Cu" "F.Mask" "F.Paste")
			(net "RST_ESPI_RESET_N_R")
		)
	)
	(footprint ""
		(layer "F.Cu")
		(at 237.401608 -403.705822)
		(property "Reference" "PR3995"
			(at 0 0 0)
			(layer "F.SilkS")
			(hide yes)
			(effects
				(font
					(size 1.27 1.27)
				)
			)
		)
		(property "Value" ""
			(at 0 0 0)
			(layer "F.Fab")
			(effects
				(font
					(size 1.27 1.27)
				)
			)
		)
		(duplicate_pad_numbers_are_jumpers no)
		(fp_line
			(start -0.7874 -0.4064)
			(end 0.7874 -0.4064)
			(stroke
				(width 0.1524)
				(type default)
			)
			(layer "F.SilkS")
		)
		(fp_line
			(start -0.7874 0.4064)
			(end -0.7874 -0.4064)
			(stroke
				(width 0.1524)
				(type default)
			)
			(layer "F.SilkS")
		)
		(fp_line
			(start 0.7874 -0.4064)
			(end 0.7874 0.4064)
			(stroke
				(width 0.1524)
				(type default)
			)
			(layer "F.SilkS")
		)
		(fp_line
			(start 0.7874 0.4064)
			(end -0.7874 0.4064)
			(stroke
				(width 0.1524)
				(type default)
			)
			(layer "F.SilkS")
		)
		(fp_line
			(start -0.67945 -0.305054)
			(end -0.12065 -0.305054)
			(stroke
				(width 0.1)
				(type default)
			)
			(layer "F.Fab")
		)
		(fp_line
			(start -0.67945 0.3048)
			(end -0.67945 -0.305054)
			(stroke
				(width 0.1)
				(type default)
			)
			(layer "F.Fab")
		)
		(fp_line
			(start -0.12065 -0.305054)
			(end -0.12065 -0.2794)
			(stroke
				(width 0.1)
				(type default)
			)
			(layer "F.Fab")
		)
		(fp_line
			(start -0.12065 -0.2794)
			(end 0.12065 -0.2794)
			(stroke
				(width 0.1)
				(type default)
			)
			(layer "F.Fab")
		)
		(fp_line
			(start -0.12065 0.2794)
			(end -0.12065 0.3048)
			(stroke
				(width 0.1)
				(type default)
			)
			(layer "F.Fab")
		)
		(fp_line
			(start -0.12065 0.3048)
			(end -0.67945 0.3048)
			(stroke
				(width 0.1)
				(type default)
			)
			(layer "F.Fab")
		)
		(fp_line
			(start 0.120396 0.2794)
			(end -0.12065 0.2794)
			(stroke
				(width 0.1)
				(type default)
			)
			(layer "F.Fab")
		)
		(fp_line
			(start 0.120396 0.3048)
			(end 0.120396 0.2794)
			(stroke
				(width 0.1)
				(type default)
			)
			(layer "F.Fab")
		)
		(fp_line
			(start 0.12065 -0.3048)
			(end 0.67945 -0.3048)
			(stroke
				(width 0.1)
				(type default)
			)
			(layer "F.Fab")
		)
		(fp_line
			(start 0.12065 -0.2794)
			(end 0.12065 -0.3048)
			(stroke
				(width 0.1)
				(type default)
			)
			(layer "F.Fab")
		)
		(fp_line
			(start 0.67945 -0.3048)
			(end 0.67945 0.3048)
			(stroke
				(width 0.1)
				(type default)
			)
			(layer "F.Fab")
		)
		(fp_line
			(start 0.67945 0.3048)
			(end 0.120396 0.3048)
			(stroke
				(width 0.1)
				(type default)
			)
			(layer "F.Fab")
		)
		(pad "1" smd circle
			(at -0.40005 0)
			(size 0 0)
			(layers "F.Cu" "F.Mask" "F.Paste")
			(net "HSC_FLT_TYPE_4")
		)
		(pad "2" smd circle
			(at 0.40005 0)
			(size 0 0)
			(layers "F.Cu" "F.Mask" "F.Paste")
			(net "HSC_FLT_TYPE")
		)
	)
	(footprint ""
		(layer "F.Cu")
		(at 434.805328 -16.188182 -90)
		(property "Reference" "R1671"
			(at 0 0 270)
			(layer "F.SilkS")
			(hide yes)
			(effects
				(font
					(size 1.27 1.27)
				)
			)
		)
		(property "Value" ""
			(at 0 0 270)
			(layer "F.Fab")
			(effects
				(font
					(size 1.27 1.27)
				)
			)
		)
		(duplicate_pad_numbers_are_jumpers no)
		(fp_line
			(start -0.7874 0.4064)
			(end -0.7874 -0.4064)
			(stroke
				(width 0.1524)
				(type default)
			)
			(layer "F.SilkS")
		)
		(fp_line
			(start 0.7874 0.4064)
			(end -0.7874 0.4064)
			(stroke
				(width 0.1524)
				(type default)
			)
			(layer "F.SilkS")
		)
		(fp_line
			(start -0.7874 -0.4064)
			(end 0.7874 -0.4064)
			(stroke
				(width 0.1524)
				(type default)
			)
			(layer "F.SilkS")
		)
		(fp_line
			(start 0.7874 -0.4064)
			(end 0.7874 0.4064)
			(stroke
				(width 0.1524)
				(type default)
			)
			(layer "F.SilkS")
		)
		(fp_line
			(start -0.67945 0.3048)
			(end -0.67945 -0.305054)
			(stroke
				(width 0.1)
				(type default)
			)
			(layer "F.Fab")
		)
		(fp_line
			(start -0.12065 0.3048)
			(end -0.67945 0.3048)
			(stroke
				(width 0.1)
				(type default)
			)
			(layer "F.Fab")
		)
		(fp_line
			(start 0.120396 0.3048)
			(end 0.120396 0.2794)
			(stroke
				(width 0.1)
				(type default)
			)
			(layer "F.Fab")
		)
		(fp_line
			(start 0.67945 0.3048)
			(end 0.120396 0.3048)
			(stroke
				(width 0.1)
				(type default)
			)
			(layer "F.Fab")
		)
		(fp_line
			(start -0.12065 0.2794)
			(end -0.12065 0.3048)
			(stroke
				(width 0.1)
				(type default)
			)
			(layer "F.Fab")
		)
		(fp_line
			(start 0.120396 0.2794)
			(end -0.12065 0.2794)
			(stroke
				(width 0.1)
				(type default)
			)
			(layer "F.Fab")
		)
		(fp_line
			(start -0.12065 -0.2794)
			(end 0.12065 -0.2794)
			(stroke
				(width 0.1)
				(type default)
			)
			(layer "F.Fab")
		)
		(fp_line
			(start 0.12065 -0.2794)
			(end 0.12065 -0.3048)
			(stroke
				(width 0.1)
				(type default)
			)
			(layer "F.Fab")
		)
		(fp_line
			(start 0.12065 -0.3048)
			(end 0.67945 -0.3048)
			(stroke
				(width 0.1)
				(type default)
			)
			(layer "F.Fab")
		)
		(fp_line
			(start 0.67945 -0.3048)
			(end 0.67945 0.3048)
			(stroke
				(width 0.1)
				(type default)
			)
			(layer "F.Fab")
		)
		(fp_line
			(start -0.67945 -0.305054)
			(end -0.12065 -0.305054)
			(stroke
				(width 0.1)
				(type default)
			)
			(layer "F.Fab")
		)
		(fp_line
			(start -0.12065 -0.305054)
			(end -0.12065 -0.2794)
			(stroke
				(width 0.1)
				(type default)
			)
			(layer "F.Fab")
		)
		(pad "1" smd circle
			(at -0.40005 0 270)
			(size 0 0)
			(layers "F.Cu" "F.Mask" "F.Paste")
			(net "OCP_SFF_AUX_PWR_EN")
		)
		(pad "2" smd circle
			(at 0.40005 0 270)
			(size 0 0)
			(layers "F.Cu" "F.Mask" "F.Paste")
			(net "OCP_SFF_AUX_PWR_EN_R")
		)
	)
	(footprint ""
		(layer "F.Cu")
		(at 435.208172 -32.173418 -90)
		(property "Reference" "R3869"
			(at 0 0 270)
			(layer "F.SilkS")
			(hide yes)
			(effects
				(font
					(size 1.27 1.27)
				)
			)
		)
		(property "Value" ""
			(at 0 0 270)
			(layer "F.Fab")
			(effects
				(font
					(size 1.27 1.27)
				)
			)
		)
		(duplicate_pad_numbers_are_jumpers no)
		(fp_line
			(start -0.7874 0.4064)
			(end -0.7874 -0.4064)
			(stroke
				(width 0.1524)
				(type default)
			)
			(layer "F.SilkS")
		)
		(fp_line
			(start 0.7874 0.4064)
			(end -0.7874 0.4064)
			(stroke
				(width 0.1524)
				(type default)
			)
			(layer "F.SilkS")
		)
		(fp_line
			(start -0.7874 -0.4064)
			(end 0.7874 -0.4064)
			(stroke
				(width 0.1524)
				(type default)
			)
			(layer "F.SilkS")
		)
		(fp_line
			(start 0.7874 -0.4064)
			(end 0.7874 0.4064)
			(stroke
				(width 0.1524)
				(type default)
			)
			(layer "F.SilkS")
		)
		(fp_line
			(start -0.67945 0.3048)
			(end -0.67945 -0.305054)
			(stroke
				(width 0.1)
				(type default)
			)
			(layer "F.Fab")
		)
		(fp_line
			(start -0.12065 0.3048)
			(end -0.67945 0.3048)
			(stroke
				(width 0.1)
				(type default)
			)
			(layer "F.Fab")
		)
		(fp_line
			(start 0.120396 0.3048)
			(end 0.120396 0.2794)
			(stroke
				(width 0.1)
				(type default)
			)
			(layer "F.Fab")
		)
		(fp_line
			(start 0.67945 0.3048)
			(end 0.120396 0.3048)
			(stroke
				(width 0.1)
				(type default)
			)
			(layer "F.Fab")
		)
		(fp_line
			(start -0.12065 0.2794)
			(end -0.12065 0.3048)
			(stroke
				(width 0.1)
				(type default)
			)
			(layer "F.Fab")
		)
		(fp_line
			(start 0.120396 0.2794)
			(end -0.12065 0.2794)
			(stroke
				(width 0.1)
				(type default)
			)
			(layer "F.Fab")
		)
		(fp_line
			(start -0.12065 -0.2794)
			(end 0.12065 -0.2794)
			(stroke
				(width 0.1)
				(type default)
			)
			(layer "F.Fab")
		)
		(fp_line
			(start 0.12065 -0.2794)
			(end 0.12065 -0.3048)
			(stroke
				(width 0.1)
				(type default)
			)
			(layer "F.Fab")
		)
		(fp_line
			(start 0.12065 -0.3048)
			(end 0.67945 -0.3048)
			(stroke
				(width 0.1)
				(type default)
			)
			(layer "F.Fab")
		)
		(fp_line
			(start 0.67945 -0.3048)
			(end 0.67945 0.3048)
			(stroke
				(width 0.1)
				(type default)
			)
			(layer "F.Fab")
		)
		(fp_line
			(start -0.67945 -0.305054)
			(end -0.12065 -0.305054)
			(stroke
				(width 0.1)
				(type default)
			)
			(layer "F.Fab")
		)
		(fp_line
			(start -0.12065 -0.305054)
			(end -0.12065 -0.2794)
			(stroke
				(width 0.1)
				(type default)
			)
			(layer "F.Fab")
		)
		(pad "1" smd rect
			(at -0.40005 0 90)
			(size 0.4572 0.508)
			(layers "F.Cu" "F.Mask" "F.Paste")
			(net "P12V_OCP_SENSE_1")
		)
		(pad "2" smd rect
			(at 0.40005 0 90)
			(size 0.4572 0.508)
			(layers "F.Cu" "F.Mask" "F.Paste")
			(net "P12V_OCP_SFF_ISENSE_MAM_MAM")
		)
	)
	(footprint ""
		(layer "F.Cu")
		(at 106.32313 -240.277142 90)
		(property "Reference" "C292"
			(at 0 0 90)
			(layer "F.SilkS")
			(hide yes)
			(effects
				(font
					(size 1.27 1.27)
				)
			)
		)
		(property "Value" ""
			(at 0 0 90)
			(layer "F.Fab")
			(effects
				(font
					(size 1.27 1.27)
				)
			)
		)
		(duplicate_pad_numbers_are_jumpers no)
		(fp_line
			(start 0.7874 -0.4064)
			(end 0.7874 0.4064)
			(stroke
				(width 0.1524)
				(type default)
			)
			(layer "F.SilkS")
		)
		(fp_line
			(start -0.7874 -0.4064)
			(end 0.7874 -0.4064)
			(stroke
				(width 0.1524)
				(type default)
			)
			(layer "F.SilkS")
		)
		(fp_line
			(start 0.7874 0.4064)
			(end -0.7874 0.4064)
			(stroke
				(width 0.1524)
				(type default)
			)
			(layer "F.SilkS")
		)
		(fp_line
			(start -0.7874 0.4064)
			(end -0.7874 -0.4064)
			(stroke
				(width 0.1524)
				(type default)
			)
			(layer "F.SilkS")
		)
		(fp_line
			(start -0.12065 -0.305054)
			(end -0.12065 -0.2794)
			(stroke
				(width 0.1)
				(type default)
			)
			(layer "F.Fab")
		)
		(fp_line
			(start -0.67945 -0.305054)
			(end -0.12065 -0.305054)
			(stroke
				(width 0.1)
				(type default)
			)
			(layer "F.Fab")
		)
		(fp_line
			(start 0.67945 -0.3048)
			(end 0.67945 0.3048)
			(stroke
				(width 0.1)
				(type default)
			)
			(layer "F.Fab")
		)
		(fp_line
			(start 0.12065 -0.3048)
			(end 0.67945 -0.3048)
			(stroke
				(width 0.1)
				(type default)
			)
			(layer "F.Fab")
		)
		(fp_line
			(start 0.12065 -0.2794)
			(end 0.12065 -0.3048)
			(stroke
				(width 0.1)
				(type default)
			)
			(layer "F.Fab")
		)
		(fp_line
			(start -0.12065 -0.2794)
			(end 0.12065 -0.2794)
			(stroke
				(width 0.1)
				(type default)
			)
			(layer "F.Fab")
		)
		(fp_line
			(start 0.120396 0.2794)
			(end -0.12065 0.2794)
			(stroke
				(width 0.1)
				(type default)
			)
			(layer "F.Fab")
		)
		(fp_line
			(start -0.12065 0.2794)
			(end -0.12065 0.3048)
			(stroke
				(width 0.1)
				(type default)
			)
			(layer "F.Fab")
		)
		(fp_line
			(start 0.67945 0.3048)
			(end 0.120396 0.3048)
			(stroke
				(width 0.1)
				(type default)
			)
			(layer "F.Fab")
		)
		(fp_line
			(start 0.120396 0.3048)
			(end 0.120396 0.2794)
			(stroke
				(width 0.1)
				(type default)
			)
			(layer "F.Fab")
		)
		(fp_line
			(start -0.12065 0.3048)
			(end -0.67945 0.3048)
			(stroke
				(width 0.1)
				(type default)
			)
			(layer "F.Fab")
		)
		(fp_line
			(start -0.67945 0.3048)
			(end -0.67945 -0.305054)
			(stroke
				(width 0.1)
				(type default)
			)
			(layer "F.Fab")
		)
		(pad "1" smd circle
			(at -0.40005 0 90)
			(size 0 0)
			(layers "F.Cu" "F.Mask" "F.Paste")
			(net "PVCCIN_CPU1")
		)
		(pad "2" smd circle
			(at 0.40005 0 90)
			(size 0 0)
			(layers "F.Cu" "F.Mask" "F.Paste")
			(net "GND")
		)
	)
)
